FILE_TYPE = MACRO_DRAWING;
SET COLOR_WIRE YELLOW;
SET COLOR_PROP ORANGE;
SET COLOR_DOT WHITE;
SET COLOR_ARC YELLOW;
SET COLOR_BODY GREEN;
SET COLOR_NOTE PURPLE;
SET PROP_DISPLAY VALUE;
SET PAGE_NUMBER P277;
FORCEADD QUANTA_TITLE_BLOCK_C..1
(9850 -200);
FORCEPROP 1 LAST CUSTOM_TXT_CDS <NAME_2>
J 0
(6675 -150);
FORCEPROP 1 LAST CUSTOM_TXT_CDS <NAME_1>
J 0
(6675 -25);
FORCEPROP 1 LAST CUSTOM_TXT_CDS <Q_NUMBER>
J 0
(8447 -97);
DISPLAY 1.212766 (8447 -97);
FORCEPROP 1 LAST CUSTOM_TXT_CDS <Q_PROJ>
J 0
(7468 -98);
DISPLAY 1.212766 (7468 -98);
FORCEPROP 1 LAST CUSTOM_TXT_CDS <Q_REV>
J 0
(9666 -97);
DISPLAY 1.212766 (9666 -97);
FORCEPROP 1 LAST CUSTOM_TXT_CDS <CON_LAST_MODIFIED>
J 0
(7965 -185);
DISPLAY 0.978723 (7965 -185);
FORCEPROP 1 LAST CUSTOM_TXT_CDS <CON_PAGE_NUM> OF <CON_TOTAL_PAGES>
J 0
(9404 -182);
DISPLAY 0.978723 (9404 -182);
FORCEPROP 1 LAST Q_TITLE BLANK
J 0
(484 -174);
DISPLAY 2.446809 (484 -174);
PAINT GREEN (484 -174);
FORCEPROP 1 LAST Q_DEPT 
J 1
(6087 -151);
DISPLAY 1.957447 (6087 -151);
PAINT GREEN (6087 -151);
FORCEPROP 2 LAST CDS_XR_PAGE_TITLE CR-291 : @S9S_MB_2U_LIB.S9S_MB_2U(SCH_1):PAGE291
J 0
(1960 5050);
DISPLAY 0.638298 (1960 5050);
PAINT PINK (1960 5050);
DISPLAY INVISIBLE (1960 5050);
FORCEPROP 1 LAST COMMENT_BODY TRUE
J 0
(9862 -213);
DISPLAY 0.978723 (9862 -213);
PAINT GREEN (9862 -213);
DISPLAY INVISIBLE (9862 -213);
FORCEPROP 2 LAST PAGE_BORDER TRUE
J 0
(1960 5050);
DISPLAY 0.638298 (1960 5050);
PAINT PINK (1960 5050);
DISPLAY INVISIBLE (1960 5050);
FORCEPROP 1 LAST CDS_LMAN_SYM_OUTLINE -9475,6775,100,-125
J 0
(9850 -200);
DISPLAY 0.468085 (9850 -200);
PAINT GREEN (9850 -200);
DISPLAY INVISIBLE (9850 -200);
FORCEPROP 2 LAST CDS_LIB pure_quanta
J 0
(9850 -200);
DISPLAY INVISIBLE (9850 -200);
FORCEPROP 2 LAST CUSTOM_TXT_CDS <XR_PAGE_TITLE>
J 0
(1960 5050);
DISPLAY 0.638298 (1960 5050);
PAINT PINK (1960 5050);
DISPLAY INVISIBLE (1960 5050);
FORCEPROP 0 LAST CDS_CON_LAST_MODIFIED Thu Aug 24 16:16:56 2023
J 0
(7965 -185);
DISPLAY INVISIBLE (7965 -185);
QUIT
